(kicad_pcb
	(version 20260206)
	(generator "pcbnew")
	(generator_version "10.0")
	(general
		(thickness 1.6)
		(legacy_teardrops no)
	)
	(paper "A4")
	(title_block
		(title "Bryce Canyon_F.DPB_16315-1-OCP.brd")
		(comment 1 "Bryce Canyon / footprints 1260-1267 of 2223")
	)
	(layers
		(0 "F.Cu" signal "TOP")
		(4 "In1.Cu" signal "L2GND")
		(6 "In2.Cu" signal "L3")
		(8 "In3.Cu" signal "L4GND")
		(10 "In4.Cu" signal "L5")
		(12 "In5.Cu" signal "L6VCC")
		(14 "In6.Cu" signal "L7VCC")
		(16 "In7.Cu" signal "L8")
		(18 "In8.Cu" signal "L9GND")
		(20 "In9.Cu" signal "L10")
		(22 "In10.Cu" signal "L11GND")
		(2 "B.Cu" signal "BOTTOM")
		(9 "F.Adhes" user "F.Adhesive")
		(11 "B.Adhes" user "B.Adhesive")
		(13 "F.Paste" user "Package Geometry/Pastemask Top")
		(15 "B.Paste" user "Package Geometry/Pastemask Bottom")
		(5 "F.SilkS" user "Ref Des/Silkscreen Top")
		(7 "B.SilkS" user "Ref Des/Silkscreen Bottom")
		(1 "F.Mask" user "Board Geometry/Soldermask Top")
		(3 "B.Mask" user "Board Geometry/Soldermask Bottom")
		(17 "Dwgs.User" user "User.Drawings")
		(19 "Cmts.User" user "User.Comments")
		(21 "Eco1.User" user "User.Eco1")
		(23 "Eco2.User" user "User.Eco2")
		(25 "Edge.Cuts" user "Board Geometry/Outline")
		(27 "Margin" user)
		(31 "F.CrtYd" user "Package Geometry/Place Bound Top")
		(29 "B.CrtYd" user "Package Geometry/Place Bound Bottom")
		(35 "F.Fab" user "Ref Des/Assembly Top")
		(33 "B.Fab" user "Ref Des/Assembly Bottom")
	)
	(footprint ""
		(layer "F.Cu")
		(at 299.962062 -74.79919)
		(property "Reference" "R204"
			(at 0 0 0)
			(layer "F.SilkS")
			(hide yes)
			(effects
				(font
					(size 1.27 1.27)
				)
			)
		)
		(property "Value" "0R2J-2-GP"
			(at 0.064008 -3.993896 0)
			(unlocked yes)
			(layer "F.Fab")
			(hide yes)
			(effects
				(font
					(size 1.016 1.016)
					(thickness 0.1524)
				)
			)
		)
		(property "Device Type" "R402H16"
			(at 0.064008 -5.517896 0)
			(unlocked yes)
			(layer "F.Fab")
			(hide yes)
			(effects
				(font
					(size 1.016 1.016)
					(thickness 0.1524)
				)
			)
		)
		(duplicate_pad_numbers_are_jumpers no)
		(fp_line
			(start -0.508 -0.9398)
			(end -0.508 0.9398)
			(stroke
				(width 0.1524)
				(type default)
			)
			(layer "F.SilkS")
		)
		(fp_line
			(start 0.508 -0.9398)
			(end -0.508 -0.9398)
			(stroke
				(width 0.1524)
				(type default)
			)
			(layer "F.SilkS")
		)
		(fp_rect
			(start -0.508 0.9398)
			(end 0.508 -0.9398)
			(stroke
				(width 0)
				(type default)
			)
			(fill no)
			(layer "F.CrtYd")
		)
		(fp_rect
			(start -0.508 0.9398)
			(end 0.508 -0.9398)
			(stroke
				(width 0)
				(type default)
			)
			(fill no)
			(layer "F.Fab")
		)
		(pad "1" smd custom
			(at 0 -0.4445)
			(size 0.1397 0.1397)
			(layers "F.Cu" "F.Mask" "F.Paste")
			(net "SLOT1_SVR_ID0_GPIO3")
			(options
				(clearance outline)
				(anchor circle)
			)
			(primitives
				(gr_poly
					(pts
						(arc
							(start -0.1778 -0.2794)
							(mid -0.249642 -0.249642)
							(end -0.2794 -0.1778)
						)
						(arc
							(start -0.2794 0.1778)
							(mid -0.249642 0.249642)
							(end -0.1778 0.2794)
						)
						(arc
							(start 0.1778 0.2794)
							(mid 0.249642 0.249642)
							(end 0.2794 0.1778)
						)
						(arc
							(start 0.2794 -0.1778)
							(mid 0.249642 -0.249642)
							(end 0.1778 -0.2794)
						)
					)
					(width 0)
					(fill yes)
				)
			)
		)
		(pad "2" smd custom
			(at 0 0.4445)
			(size 0.1397 0.1397)
			(layers "F.Cu" "F.Mask" "F.Paste")
			(net "COMP_B_TO_BMC_B_RESET_N")
			(options
				(clearance outline)
				(anchor circle)
			)
			(primitives
				(gr_poly
					(pts
						(arc
							(start -0.1778 -0.2794)
							(mid -0.249642 -0.249642)
							(end -0.2794 -0.1778)
						)
						(arc
							(start -0.2794 0.1778)
							(mid -0.249642 0.249642)
							(end -0.1778 0.2794)
						)
						(arc
							(start 0.1778 0.2794)
							(mid 0.249642 0.249642)
							(end 0.2794 0.1778)
						)
						(arc
							(start 0.2794 -0.1778)
							(mid 0.249642 -0.249642)
							(end 0.1778 -0.2794)
						)
					)
					(width 0)
					(fill yes)
				)
			)
		)
	)
	(footprint ""
		(layer "F.Cu")
		(at 299.66031 -71.461122 -90)
		(property "Reference" "C28"
			(at 0 0 270)
			(layer "F.SilkS")
			(hide yes)
			(effects
				(font
					(size 1.27 1.27)
				)
			)
		)
		(property "Value" "SCD1U16V2KX-3GP"
			(at 1.1811 -2.7051 270)
			(unlocked yes)
			(layer "F.Fab")
			(hide yes)
			(effects
				(font
					(size 1.016 1.016)
					(thickness 0.1524)
				)
			)
		)
		(property "Device Type" "C402H22"
			(at 1.1811 -4.2291 270)
			(unlocked yes)
			(layer "F.Fab")
			(hide yes)
			(effects
				(font
					(size 1.016 1.016)
					(thickness 0.1524)
				)
			)
		)
		(duplicate_pad_numbers_are_jumpers no)
		(fp_rect
			(start -0.4318 0.9525)
			(end 0.4318 -0.9525)
			(stroke
				(width 0)
				(type default)
			)
			(fill no)
			(layer "F.CrtYd")
		)
		(fp_rect
			(start -0.4318 0.9525)
			(end 0.4318 -0.9525)
			(stroke
				(width 0)
				(type default)
			)
			(fill no)
			(layer "F.Fab")
		)
		(pad "1" smd custom
			(at 0 -0.4445 270)
			(size 0.1524 0.1524)
			(layers "F.Cu" "F.Mask" "F.Paste")
			(net "P3V3_STBY_B")
			(options
				(clearance outline)
				(anchor circle)
			)
			(primitives
				(gr_poly
					(pts
						(arc
							(start 0.3048 -0.2032)
							(mid 0.275042 -0.275042)
							(end 0.2032 -0.3048)
						)
						(arc
							(start -0.2032 -0.3048)
							(mid -0.275042 -0.275042)
							(end -0.3048 -0.2032)
						)
						(arc
							(start -0.3048 0.2032)
							(mid -0.275042 0.275042)
							(end -0.2032 0.3048)
						)
						(arc
							(start 0.2032 0.3048)
							(mid 0.275042 0.275042)
							(end 0.3048 0.2032)
						)
					)
					(width 0)
					(fill yes)
				)
			)
		)
		(pad "2" smd custom
			(at 0 0.4445 270)
			(size 0.1524 0.1524)
			(layers "F.Cu" "F.Mask" "F.Paste")
			(net "GND")
			(options
				(clearance outline)
				(anchor circle)
			)
			(primitives
				(gr_poly
					(pts
						(arc
							(start 0.3048 -0.2032)
							(mid 0.275042 -0.275042)
							(end 0.2032 -0.3048)
						)
						(arc
							(start -0.2032 -0.3048)
							(mid -0.275042 -0.275042)
							(end -0.3048 -0.2032)
						)
						(arc
							(start -0.3048 0.2032)
							(mid -0.275042 0.275042)
							(end -0.2032 0.3048)
						)
						(arc
							(start 0.2032 0.3048)
							(mid 0.275042 0.275042)
							(end 0.3048 0.2032)
						)
					)
					(width 0)
					(fill yes)
				)
			)
		)
	)
	(footprint ""
		(layer "F.Cu")
		(at 64.0588 -277.750016 -90)
		(property "Reference" "VIA36"
			(at 0 0 270)
			(layer "F.SilkS")
			(hide yes)
			(effects
				(font
					(size 1.27 1.27)
				)
			)
		)
		(property "Value" "100OHM-8L-1D6MM-L18L16-GP"
			(at -3.7211 -4.5085 270)
			(unlocked yes)
			(layer "F.Fab")
			(hide yes)
			(effects
				(font
					(size 1.016 1.016)
					(thickness 0.1524)
				)
			)
		)
		(property "Device Type" "VIA-PCIE-4P-394076"
			(at -3.7211 -6.0325 270)
			(unlocked yes)
			(layer "F.Fab")
			(hide yes)
			(effects
				(font
					(size 1.016 1.016)
					(thickness 0.1524)
				)
			)
		)
		(duplicate_pad_numbers_are_jumpers no)
		(fp_rect
			(start -1.9685 0.381)
			(end 1.9685 -0.381)
			(stroke
				(width 0)
				(type default)
			)
			(fill no)
			(layer "F.CrtYd")
		)
		(fp_rect
			(start -1.9685 0.381)
			(end 1.9685 -0.381)
			(stroke
				(width 0)
				(type default)
			)
			(fill no)
			(layer "F.Fab")
		)
		(pad "1" thru_hole circle
			(at -1.5875 0 270)
			(size 0.508 0.508)
			(drill 0.254)
			(layers "*.Cu" "*.Mask")
			(remove_unused_layers no)
			(net "GND")
			(clearance 0.127)
			(thermal_gap 0.127)
		)
		(pad "2" thru_hole circle
			(at -0.5715 0 270)
			(size 0.508 0.508)
			(drill 0.254)
			(layers "*.Cu" "*.Mask")
			(remove_unused_layers no)
			(net "PHY_DRV_A_TO_SCC_A_1_DP")
			(clearance 0.127)
			(thermal_gap 0.127)
		)
		(pad "3" thru_hole circle
			(at 0.5715 0 270)
			(size 0.508 0.508)
			(drill 0.254)
			(layers "*.Cu" "*.Mask")
			(remove_unused_layers no)
			(net "PHY_DRV_A_TO_SCC_A_1_DN")
			(clearance 0.127)
			(thermal_gap 0.127)
		)
		(pad "4" thru_hole circle
			(at 1.5875 0 270)
			(size 0.508 0.508)
			(drill 0.254)
			(layers "*.Cu" "*.Mask")
			(remove_unused_layers no)
			(net "GND")
			(clearance 0.127)
			(thermal_gap 0.127)
		)
	)
	(footprint ""
		(layer "F.Cu")
		(at 181.6862 -301.287942)
		(property "Reference" "C109"
			(at 0 0 0)
			(layer "F.SilkS")
			(hide yes)
			(effects
				(font
					(size 1.27 1.27)
				)
			)
		)
		(property "Value" "SC4D7U25V5KX-1-GP"
			(at -0.0762 -6.1214 0)
			(unlocked yes)
			(layer "F.Fab")
			(hide yes)
			(effects
				(font
					(size 1.016 1.016)
					(thickness 0.1524)
				)
			)
		)
		(property "Device Type" "C805H58"
			(at -0.0762 -8.1534 0)
			(unlocked yes)
			(layer "F.Fab")
			(hide yes)
			(effects
				(font
					(size 1.016 1.016)
					(thickness 0.1524)
				)
			)
		)
		(duplicate_pad_numbers_are_jumpers no)
		(fp_line
			(start 0.635 0)
			(end -0.635 0)
			(stroke
				(width 0.508)
				(type default)
			)
			(layer "F.SilkS")
		)
		(fp_rect
			(start -0.9652 1.778)
			(end 0.9652 -1.778)
			(stroke
				(width 0)
				(type default)
			)
			(fill no)
			(layer "F.CrtYd")
		)
		(fp_poly
			(pts
				(xy -0.9652 -1.778) (xy 0.9652 -1.778) (xy 0.9652 1.778) (xy -0.9652 1.778)
			)
			(stroke
				(width 0)
				(type default)
			)
			(fill no)
			(layer "F.Fab")
		)
		(pad "1" smd rect
			(at 0 -0.9652)
			(size 1.397 1.143)
			(layers "F.Cu" "F.Mask" "F.Paste")
			(net "P12V_HDD5")
		)
		(pad "2" smd rect
			(at 0 0.9652)
			(size 1.397 1.143)
			(layers "F.Cu" "F.Mask" "F.Paste")
			(net "GND")
		)
	)
	(footprint ""
		(layer "F.Cu")
		(at 79.581248 -26.931874)
		(property "Reference" "C11"
			(at 0 0 0)
			(layer "F.SilkS")
			(hide yes)
			(effects
				(font
					(size 1.27 1.27)
				)
			)
		)
		(property "Value" "SC1U16V3KX-5GP"
			(at 0 -2.8194 0)
			(unlocked yes)
			(layer "F.Fab")
			(hide yes)
			(effects
				(font
					(size 1.016 1.016)
					(thickness 0.1524)
				)
			)
		)
		(property "Device Type" "C603H36"
			(at 0 -4.3434 0)
			(unlocked yes)
			(layer "F.Fab")
			(hide yes)
			(effects
				(font
					(size 1.016 1.016)
					(thickness 0.1524)
				)
			)
		)
		(duplicate_pad_numbers_are_jumpers no)
		(fp_line
			(start 0.508 0)
			(end -0.508 0)
			(stroke
				(width 0.2032)
				(type default)
			)
			(layer "F.SilkS")
		)
		(fp_rect
			(start -0.5842 1.3335)
			(end 0.5842 -1.3335)
			(stroke
				(width 0)
				(type default)
			)
			(fill no)
			(layer "F.CrtYd")
		)
		(fp_rect
			(start -0.5842 1.3335)
			(end 0.5842 -1.3335)
			(stroke
				(width 0)
				(type default)
			)
			(fill no)
			(layer "F.Fab")
		)
		(pad "1" smd custom
			(at 0 -0.762)
			(size 0.2159 0.2159)
			(layers "F.Cu" "F.Mask" "F.Paste")
			(net "P3V3_STBY_A")
			(options
				(clearance outline)
				(anchor circle)
			)
			(primitives
				(gr_poly
					(pts
						(arc
							(start -0.3302 -0.4318)
							(mid -0.402042 -0.402042)
							(end -0.4318 -0.3302)
						)
						(arc
							(start -0.4318 0.3302)
							(mid -0.402042 0.402042)
							(end -0.3302 0.4318)
						)
						(arc
							(start 0.3302 0.4318)
							(mid 0.402042 0.402042)
							(end 0.4318 0.3302)
						)
						(arc
							(start 0.4318 -0.3302)
							(mid 0.402042 -0.402042)
							(end 0.3302 -0.4318)
						)
					)
					(width 0)
					(fill yes)
				)
			)
		)
		(pad "2" smd custom
			(at 0 0.762)
			(size 0.2159 0.2159)
			(layers "F.Cu" "F.Mask" "F.Paste")
			(net "GND")
			(options
				(clearance outline)
				(anchor circle)
			)
			(primitives
				(gr_poly
					(pts
						(arc
							(start -0.3302 -0.4318)
							(mid -0.402042 -0.402042)
							(end -0.4318 -0.3302)
						)
						(arc
							(start -0.4318 0.3302)
							(mid -0.402042 0.402042)
							(end -0.3302 0.4318)
						)
						(arc
							(start 0.3302 0.4318)
							(mid 0.402042 0.402042)
							(end 0.4318 0.3302)
						)
						(arc
							(start 0.4318 -0.3302)
							(mid 0.402042 -0.402042)
							(end 0.3302 -0.4318)
						)
					)
					(width 0)
					(fill yes)
				)
			)
		)
	)
	(footprint ""
		(layer "F.Cu")
		(at 468.735918 -156.522674 180)
		(property "Reference" "R667"
			(at 0 0 180)
			(layer "F.SilkS")
			(hide yes)
			(effects
				(font
					(size 1.27 1.27)
				)
			)
		)
		(property "Value" "1KR2F-3-GP"
			(at 0.064008 -3.993896 180)
			(unlocked yes)
			(layer "F.Fab")
			(hide yes)
			(effects
				(font
					(size 1.016 1.016)
					(thickness 0.1524)
				)
			)
		)
		(property "Device Type" "R402H16"
			(at 0.064008 -5.517896 180)
			(unlocked yes)
			(layer "F.Fab")
			(hide yes)
			(effects
				(font
					(size 1.016 1.016)
					(thickness 0.1524)
				)
			)
		)
		(duplicate_pad_numbers_are_jumpers no)
		(fp_line
			(start 0.508 -0.9398)
			(end -0.508 -0.9398)
			(stroke
				(width 0.1524)
				(type default)
			)
			(layer "F.SilkS")
		)
		(fp_line
			(start -0.508 -0.9398)
			(end -0.508 0.9398)
			(stroke
				(width 0.1524)
				(type default)
			)
			(layer "F.SilkS")
		)
		(fp_rect
			(start -0.508 0.9398)
			(end 0.508 -0.9398)
			(stroke
				(width 0)
				(type default)
			)
			(fill no)
			(layer "F.CrtYd")
		)
		(fp_rect
			(start -0.508 0.9398)
			(end 0.508 -0.9398)
			(stroke
				(width 0)
				(type default)
			)
			(fill no)
			(layer "F.Fab")
		)
		(pad "1" smd custom
			(at 0 -0.4445 180)
			(size 0.1397 0.1397)
			(layers "F.Cu" "F.Mask" "F.Paste")
			(net "P3V3_STBY_A")
			(options
				(clearance outline)
				(anchor circle)
			)
			(primitives
				(gr_poly
					(pts
						(arc
							(start -0.1778 -0.2794)
							(mid -0.249642 -0.249642)
							(end -0.2794 -0.1778)
						)
						(arc
							(start -0.2794 0.1778)
							(mid -0.249642 0.249642)
							(end -0.1778 0.2794)
						)
						(arc
							(start 0.1778 0.2794)
							(mid 0.249642 0.249642)
							(end 0.2794 0.1778)
						)
						(arc
							(start 0.2794 -0.1778)
							(mid 0.249642 -0.249642)
							(end 0.1778 -0.2794)
						)
					)
					(width 0)
					(fill yes)
				)
			)
		)
		(pad "2" smd custom
			(at 0 0.4445 180)
			(size 0.1397 0.1397)
			(layers "F.Cu" "F.Mask" "F.Paste")
			(net "SW_PWR_R_HDD23")
			(options
				(clearance outline)
				(anchor circle)
			)
			(primitives
				(gr_poly
					(pts
						(arc
							(start -0.1778 -0.2794)
							(mid -0.249642 -0.249642)
							(end -0.2794 -0.1778)
						)
						(arc
							(start -0.2794 0.1778)
							(mid -0.249642 0.249642)
							(end -0.1778 0.2794)
						)
						(arc
							(start 0.1778 0.2794)
							(mid 0.249642 0.249642)
							(end 0.2794 0.1778)
						)
						(arc
							(start 0.2794 -0.1778)
							(mid 0.249642 -0.249642)
							(end 0.1778 -0.2794)
						)
					)
					(width 0)
					(fill yes)
				)
			)
		)
	)
	(footprint ""
		(layer "F.Cu")
		(at 424.469052 -181.842918 180)
		(property "Reference" "C313"
			(at 0 0 180)
			(layer "F.SilkS")
			(hide yes)
			(effects
				(font
					(size 1.27 1.27)
				)
			)
		)
		(property "Value" "SC1U16V3KX-5GP"
			(at 0 -2.8194 180)
			(unlocked yes)
			(layer "F.Fab")
			(hide yes)
			(effects
				(font
					(size 1.016 1.016)
					(thickness 0.1524)
				)
			)
		)
		(property "Device Type" "C603H36"
			(at 0 -4.3434 180)
			(unlocked yes)
			(layer "F.Fab")
			(hide yes)
			(effects
				(font
					(size 1.016 1.016)
					(thickness 0.1524)
				)
			)
		)
		(duplicate_pad_numbers_are_jumpers no)
		(fp_line
			(start 0.508 0)
			(end -0.508 0)
			(stroke
				(width 0.2032)
				(type default)
			)
			(layer "F.SilkS")
		)
		(fp_rect
			(start -0.5842 1.3335)
			(end 0.5842 -1.3335)
			(stroke
				(width 0)
				(type default)
			)
			(fill no)
			(layer "F.CrtYd")
		)
		(fp_rect
			(start -0.5842 1.3335)
			(end 0.5842 -1.3335)
			(stroke
				(width 0)
				(type default)
			)
			(fill no)
			(layer "F.Fab")
		)
		(pad "1" smd custom
			(at 0 -0.762 180)
			(size 0.2159 0.2159)
			(layers "F.Cu" "F.Mask" "F.Paste")
			(net "P5V_HDD21")
			(options
				(clearance outline)
				(anchor circle)
			)
			(primitives
				(gr_poly
					(pts
						(arc
							(start -0.3302 -0.4318)
							(mid -0.402042 -0.402042)
							(end -0.4318 -0.3302)
						)
						(arc
							(start -0.4318 0.3302)
							(mid -0.402042 0.402042)
							(end -0.3302 0.4318)
						)
						(arc
							(start 0.3302 0.4318)
							(mid 0.402042 0.402042)
							(end 0.4318 0.3302)
						)
						(arc
							(start 0.4318 -0.3302)
							(mid 0.402042 -0.402042)
							(end 0.3302 -0.4318)
						)
					)
					(width 0)
					(fill yes)
				)
			)
		)
		(pad "2" smd custom
			(at 0 0.762 180)
			(size 0.2159 0.2159)
			(layers "F.Cu" "F.Mask" "F.Paste")
			(net "GND")
			(options
				(clearance outline)
				(anchor circle)
			)
			(primitives
				(gr_poly
					(pts
						(arc
							(start -0.3302 -0.4318)
							(mid -0.402042 -0.402042)
							(end -0.4318 -0.3302)
						)
						(arc
							(start -0.4318 0.3302)
							(mid -0.402042 0.402042)
							(end -0.3302 0.4318)
						)
						(arc
							(start 0.3302 0.4318)
							(mid 0.402042 0.402042)
							(end 0.4318 0.3302)
						)
						(arc
							(start 0.4318 -0.3302)
							(mid 0.402042 -0.402042)
							(end 0.3302 -0.4318)
						)
					)
					(width 0)
					(fill yes)
				)
			)
		)
	)
	(footprint ""
		(layer "F.Cu")
		(at 233.834178 -244.114828)
		(property "Reference" "R74"
			(at 0 0 0)
			(layer "F.SilkS")
			(hide yes)
			(effects
				(font
					(size 1.27 1.27)
				)
			)
		)
		(property "Value" "4K7R2F-GP"
			(at 0.064008 -3.993896 0)
			(unlocked yes)
			(layer "F.Fab")
			(hide yes)
			(effects
				(font
					(size 1.016 1.016)
					(thickness 0.1524)
				)
			)
		)
		(property "Device Type" "R402H16"
			(at 0.064008 -5.517896 0)
			(unlocked yes)
			(layer "F.Fab")
			(hide yes)
			(effects
				(font
					(size 1.016 1.016)
					(thickness 0.1524)
				)
			)
		)
		(duplicate_pad_numbers_are_jumpers no)
		(fp_line
			(start -0.508 -0.9398)
			(end -0.508 0.9398)
			(stroke
				(width 0.1524)
				(type default)
			)
			(layer "F.SilkS")
		)
		(fp_line
			(start 0.508 -0.9398)
			(end -0.508 -0.9398)
			(stroke
				(width 0.1524)
				(type default)
			)
			(layer "F.SilkS")
		)
		(fp_rect
			(start -0.508 0.9398)
			(end 0.508 -0.9398)
			(stroke
				(width 0)
				(type default)
			)
			(fill no)
			(layer "F.CrtYd")
		)
		(fp_rect
			(start -0.508 0.9398)
			(end 0.508 -0.9398)
			(stroke
				(width 0)
				(type default)
			)
			(fill no)
			(layer "F.Fab")
		)
		(pad "1" smd custom
			(at 0 -0.4445)
			(size 0.1397 0.1397)
			(layers "F.Cu" "F.Mask" "F.Paste")
			(net "P3V3_STBY_A")
			(options
				(clearance outline)
				(anchor circle)
			)
			(primitives
				(gr_poly
					(pts
						(arc
							(start -0.1778 -0.2794)
							(mid -0.249642 -0.249642)
							(end -0.2794 -0.1778)
						)
						(arc
							(start -0.2794 0.1778)
							(mid -0.249642 0.249642)
							(end -0.1778 0.2794)
						)
						(arc
							(start 0.1778 0.2794)
							(mid 0.249642 0.249642)
							(end 0.2794 0.1778)
						)
						(arc
							(start 0.2794 -0.1778)
							(mid 0.249642 -0.249642)
							(end 0.1778 -0.2794)
						)
					)
					(width 0)
					(fill yes)
				)
			)
		)
		(pad "2" smd custom
			(at 0 0.4445)
			(size 0.1397 0.1397)
			(layers "F.Cu" "F.Mask" "F.Paste")
			(net "IO_EXP1_A2")
			(options
				(clearance outline)
				(anchor circle)
			)
			(primitives
				(gr_poly
					(pts
						(arc
							(start -0.1778 -0.2794)
							(mid -0.249642 -0.249642)
							(end -0.2794 -0.1778)
						)
						(arc
							(start -0.2794 0.1778)
							(mid -0.249642 0.249642)
							(end -0.1778 0.2794)
						)
						(arc
							(start 0.1778 0.2794)
							(mid 0.249642 0.249642)
							(end 0.2794 0.1778)
						)
						(arc
							(start 0.2794 -0.1778)
							(mid 0.249642 -0.249642)
							(end 0.1778 -0.2794)
						)
					)
					(width 0)
					(fill yes)
				)
			)
		)
	)
)
